# T6G (Grand Teton) — schematic netlist excerpt (pin names and nets, part order shuffled) for the footprints in the layout excerpt that follows; sources: Cadence DE-HDL packaged netlist, KiCad conversion of 04192023_DAF0TMB3IC0_F0TG_MB_C_brd_V02_OCP.brd

R3033  Q_RES  0 5% CHIP  pkg 0402LF  page 130 : A = UART_BMC_BIC_RX ; B = UART_BMC_BIC_R_RX
R197  Q_RES  0 5% CHIP  pkg 0402LF  page 81 : A = RST_CPU1_PERST0_N ; B = RST_CPU1_PERST0_R_N

(kicad_pcb
	(version 20260206)
	(generator "pcbnew")
	(generator_version "10.0")
	(general
		(thickness 1.6)
		(legacy_teardrops no)
	)
	(paper "A4")
	(title_block
		(title "04192023_DAF0TMB3IC0_F0TG_MB_C_brd_V02_OCP.brd")
		(comment 1 "Grand Teton / footprints 70-71 of 8354")
	)
	(layers
		(0 "F.Cu" signal "TOP")
		(4 "In1.Cu" signal "GND")
		(6 "In2.Cu" signal "IN1")
		(8 "In3.Cu" signal "GND1")
		(10 "In4.Cu" signal "IN2")
		(12 "In5.Cu" signal "GND2")
		(14 "In6.Cu" signal "IN3")
		(16 "In7.Cu" signal "GND3")
		(18 "In8.Cu" signal "VCC")
		(20 "In9.Cu" signal "VCC1")
		(22 "In10.Cu" signal "GND4")
		(24 "In11.Cu" signal "IN4")
		(26 "In12.Cu" signal "GND5")
		(28 "In13.Cu" signal "IN5")
		(30 "In14.Cu" signal "GND6")
		(32 "In15.Cu" signal "IN6")
		(34 "In16.Cu" signal "GND7")
		(2 "B.Cu" signal "BOTTOM")
		(9 "F.Adhes" user "F.Adhesive")
		(11 "B.Adhes" user "B.Adhesive")
		(13 "F.Paste" user "Package Geometry/Pastemask Top")
		(15 "B.Paste" user "Package Geometry/Pastemask Bottom")
		(5 "F.SilkS" user "Ref Des/Silkscreen Top")
		(7 "B.SilkS" user "Ref Des/Silkscreen Bottom")
		(1 "F.Mask" user "Board Geometry/Soldermask Top")
		(3 "B.Mask" user "Board Geometry/Soldermask Bottom")
		(17 "Dwgs.User" user "User.Drawings")
		(19 "Cmts.User" user "User.Comments")
		(21 "Eco1.User" user "User.Eco1")
		(23 "Eco2.User" user "User.Eco2")
		(25 "Edge.Cuts" user "Board Geometry/Outline")
		(27 "Margin" user)
		(31 "F.CrtYd" user "Package Geometry/Place Bound Top")
		(29 "B.CrtYd" user "Package Geometry/Place Bound Bottom")
		(35 "F.Fab" user "Ref Des/Assembly Top")
		(33 "B.Fab" user "Ref Des/Assembly Bottom")
	)
	(footprint ""
		(layer "F.Cu")
		(at 177.927 -133.568948 -90)
		(property "Reference" "R197"
			(at 0 0 270)
			(layer "F.SilkS")
			(hide yes)
			(effects
				(font
					(size 1.27 1.27)
				)
			)
		)
		(property "Value" ""
			(at 0 0 270)
			(layer "F.Fab")
			(effects
				(font
					(size 1.27 1.27)
				)
			)
		)
		(duplicate_pad_numbers_are_jumpers no)
		(fp_line
			(start -0.7874 0.4064)
			(end -0.7874 -0.4064)
			(stroke
				(width 0.1524)
				(type default)
			)
			(layer "F.SilkS")
		)
		(fp_line
			(start 0.7874 0.4064)
			(end -0.7874 0.4064)
			(stroke
				(width 0.1524)
				(type default)
			)
			(layer "F.SilkS")
		)
		(fp_line
			(start -0.7874 -0.4064)
			(end 0.7874 -0.4064)
			(stroke
				(width 0.1524)
				(type default)
			)
			(layer "F.SilkS")
		)
		(fp_line
			(start 0.7874 -0.4064)
			(end 0.7874 0.4064)
			(stroke
				(width 0.1524)
				(type default)
			)
			(layer "F.SilkS")
		)
		(fp_line
			(start -0.67945 0.3048)
			(end -0.67945 -0.305054)
			(stroke
				(width 0.1)
				(type default)
			)
			(layer "F.Fab")
		)
		(fp_line
			(start -0.12065 0.3048)
			(end -0.67945 0.3048)
			(stroke
				(width 0.1)
				(type default)
			)
			(layer "F.Fab")
		)
		(fp_line
			(start 0.120396 0.3048)
			(end 0.120396 0.2794)
			(stroke
				(width 0.1)
				(type default)
			)
			(layer "F.Fab")
		)
		(fp_line
			(start 0.67945 0.3048)
			(end 0.120396 0.3048)
			(stroke
				(width 0.1)
				(type default)
			)
			(layer "F.Fab")
		)
		(fp_line
			(start -0.12065 0.2794)
			(end -0.12065 0.3048)
			(stroke
				(width 0.1)
				(type default)
			)
			(layer "F.Fab")
		)
		(fp_line
			(start 0.120396 0.2794)
			(end -0.12065 0.2794)
			(stroke
				(width 0.1)
				(type default)
			)
			(layer "F.Fab")
		)
		(fp_line
			(start -0.12065 -0.2794)
			(end 0.12065 -0.2794)
			(stroke
				(width 0.1)
				(type default)
			)
			(layer "F.Fab")
		)
		(fp_line
			(start 0.12065 -0.2794)
			(end 0.12065 -0.3048)
			(stroke
				(width 0.1)
				(type default)
			)
			(layer "F.Fab")
		)
		(fp_line
			(start 0.12065 -0.3048)
			(end 0.67945 -0.3048)
			(stroke
				(width 0.1)
				(type default)
			)
			(layer "F.Fab")
		)
		(fp_line
			(start 0.67945 -0.3048)
			(end 0.67945 0.3048)
			(stroke
				(width 0.1)
				(type default)
			)
			(layer "F.Fab")
		)
		(fp_line
			(start -0.67945 -0.305054)
			(end -0.12065 -0.305054)
			(stroke
				(width 0.1)
				(type default)
			)
			(layer "F.Fab")
		)
		(fp_line
			(start -0.12065 -0.305054)
			(end -0.12065 -0.2794)
			(stroke
				(width 0.1)
				(type default)
			)
			(layer "F.Fab")
		)
		(pad "1" smd circle
			(at -0.40005 0 270)
			(size 0 0)
			(layers "F.Cu" "F.Mask" "F.Paste")
			(net "RST_CPU1_PERST0_N")
		)
		(pad "2" smd circle
			(at 0.40005 0 270)
			(size 0 0)
			(layers "F.Cu" "F.Mask" "F.Paste")
			(net "RST_CPU1_PERST0_R_N")
		)
	)
	(footprint ""
		(layer "F.Cu")
		(at 359.567988 -409.388818 90)
		(property "Reference" "R3033"
			(at 0 0 90)
			(layer "F.SilkS")
			(hide yes)
			(effects
				(font
					(size 1.27 1.27)
				)
			)
		)
		(property "Value" ""
			(at 0 0 90)
			(layer "F.Fab")
			(effects
				(font
					(size 1.27 1.27)
				)
			)
		)
		(duplicate_pad_numbers_are_jumpers no)
		(fp_line
			(start 0.7874 -0.4064)
			(end 0.7874 0.4064)
			(stroke
				(width 0.1524)
				(type default)
			)
			(layer "F.SilkS")
		)
		(fp_line
			(start -0.7874 -0.4064)
			(end 0.7874 -0.4064)
			(stroke
				(width 0.1524)
				(type default)
			)
			(layer "F.SilkS")
		)
		(fp_line
			(start 0.7874 0.4064)
			(end -0.7874 0.4064)
			(stroke
				(width 0.1524)
				(type default)
			)
			(layer "F.SilkS")
		)
		(fp_line
			(start -0.7874 0.4064)
			(end -0.7874 -0.4064)
			(stroke
				(width 0.1524)
				(type default)
			)
			(layer "F.SilkS")
		)
		(fp_line
			(start -0.12065 -0.305054)
			(end -0.12065 -0.2794)
			(stroke
				(width 0.1)
				(type default)
			)
			(layer "F.Fab")
		)
		(fp_line
			(start -0.67945 -0.305054)
			(end -0.12065 -0.305054)
			(stroke
				(width 0.1)
				(type default)
			)
			(layer "F.Fab")
		)
		(fp_line
			(start 0.67945 -0.3048)
			(end 0.67945 0.3048)
			(stroke
				(width 0.1)
				(type default)
			)
			(layer "F.Fab")
		)
		(fp_line
			(start 0.12065 -0.3048)
			(end 0.67945 -0.3048)
			(stroke
				(width 0.1)
				(type default)
			)
			(layer "F.Fab")
		)
		(fp_line
			(start 0.12065 -0.2794)
			(end 0.12065 -0.3048)
			(stroke
				(width 0.1)
				(type default)
			)
			(layer "F.Fab")
		)
		(fp_line
			(start -0.12065 -0.2794)
			(end 0.12065 -0.2794)
			(stroke
				(width 0.1)
				(type default)
			)
			(layer "F.Fab")
		)
		(fp_line
			(start 0.120396 0.2794)
			(end -0.12065 0.2794)
			(stroke
				(width 0.1)
				(type default)
			)
			(layer "F.Fab")
		)
		(fp_line
			(start -0.12065 0.2794)
			(end -0.12065 0.3048)
			(stroke
				(width 0.1)
				(type default)
			)
			(layer "F.Fab")
		)
		(fp_line
			(start 0.67945 0.3048)
			(end 0.120396 0.3048)
			(stroke
				(width 0.1)
				(type default)
			)
			(layer "F.Fab")
		)
		(fp_line
			(start 0.120396 0.3048)
			(end 0.120396 0.2794)
			(stroke
				(width 0.1)
				(type default)
			)
			(layer "F.Fab")
		)
		(fp_line
			(start -0.12065 0.3048)
			(end -0.67945 0.3048)
			(stroke
				(width 0.1)
				(type default)
			)
			(layer "F.Fab")
		)
		(fp_line
			(start -0.67945 0.3048)
			(end -0.67945 -0.305054)
			(stroke
				(width 0.1)
				(type default)
			)
			(layer "F.Fab")
		)
		(pad "1" smd circle
			(at -0.40005 0 90)
			(size 0 0)
			(layers "F.Cu" "F.Mask" "F.Paste")
			(net "UART_BMC_BIC_RX")
		)
		(pad "2" smd circle
			(at 0.40005 0 90)
			(size 0 0)
			(layers "F.Cu" "F.Mask" "F.Paste")
			(net "UART_BMC_BIC_R_RX")
		)
	)
)
